(kicad_pcb
	(version 20260206)
	(generator "pcbnew")
	(generator_version "10.0")
	(general
		(thickness 1.6)
		(legacy_teardrops no)
	)
	(paper "A4")
	(title_block
		(title "v1-pdb — T6M_PDB_D_0927_0900.brd")
		(comment 1 "Open CloudServer (Microsoft) / footprints 13-18 of 321")
	)
	(layers
		(0 "F.Cu" signal "TOP")
		(4 "In1.Cu" signal "GND")
		(6 "In2.Cu" signal "IN1")
		(8 "In3.Cu" signal "VCC")
		(10 "In4.Cu" signal "VCC1")
		(12 "In5.Cu" signal "IN2")
		(14 "In6.Cu" signal "GND1")
		(2 "B.Cu" signal "BOTTOM")
		(9 "F.Adhes" user "F.Adhesive")
		(11 "B.Adhes" user "B.Adhesive")
		(13 "F.Paste" user "Package Geometry/Pastemask Top")
		(15 "B.Paste" user "Package Geometry/Pastemask Bottom")
		(5 "F.SilkS" user "Ref Des/Silkscreen Top")
		(7 "B.SilkS" user "Ref Des/Silkscreen Bottom")
		(1 "F.Mask" user "Board Geometry/Soldermask Top")
		(3 "B.Mask" user "Board Geometry/Soldermask Bottom")
		(17 "Dwgs.User" user "User.Drawings")
		(19 "Cmts.User" user "User.Comments")
		(21 "Eco1.User" user "User.Eco1")
		(23 "Eco2.User" user "User.Eco2")
		(25 "Edge.Cuts" user "Board Geometry/Outline")
		(27 "Margin" user)
		(31 "F.CrtYd" user "Package Geometry/Place Bound Top")
		(29 "B.CrtYd" user "Package Geometry/Place Bound Bottom")
		(35 "F.Fab" user "Ref Des/Assembly Top")
		(33 "B.Fab" user "Ref Des/Assembly Bottom")
	)
	(footprint ""
		(layer "F.Cu")
		(at 27.05481 -11.75639 180)
		(property "Reference" "R49"
			(at 3.972306 0.169926 0)
			(unlocked yes)
			(layer "F.SilkS")
			(effects
				(font
					(size 0.7874 0.5842)
					(thickness 0.1524)
				)
				(justify left)
			)
		)
		(property "Value" ""
			(at 0 0 180)
			(layer "F.Fab")
			(effects
				(font
					(size 1.27 1.27)
				)
			)
		)
		(duplicate_pad_numbers_are_jumpers no)
		(fp_line
			(start 0.7874 0.4064)
			(end -0.7874 0.4064)
			(stroke
				(width 0.1524)
				(type default)
			)
			(layer "F.SilkS")
		)
		(fp_line
			(start 0.7874 -0.4064)
			(end 0.7874 0.4064)
			(stroke
				(width 0.1524)
				(type default)
			)
			(layer "F.SilkS")
		)
		(fp_line
			(start -0.7874 0.4064)
			(end -0.7874 -0.4064)
			(stroke
				(width 0.1524)
				(type default)
			)
			(layer "F.SilkS")
		)
		(fp_line
			(start -0.7874 -0.4064)
			(end 0.7874 -0.4064)
			(stroke
				(width 0.1524)
				(type default)
			)
			(layer "F.SilkS")
		)
		(fp_poly
			(pts
				(xy -0.508 0.2794) (xy -0.508 0.2286) (xy -0.635 0.2286) (xy -0.635 -0.254) (xy -0.5334 -0.254)
				(xy -0.5334 -0.2794) (xy 0.5334 -0.2794) (xy 0.5334 -0.254) (xy 0.635 -0.254) (xy 0.635 0.254) (xy 0.5334 0.254)
				(xy 0.5334 0.2794)
			)
			(stroke
				(width 0)
				(type default)
			)
			(fill no)
			(layer "F.CrtYd")
		)
		(pad "1" smd rect
			(at 0.40005 0 180)
			(size 0.4572 0.508)
			(layers "F.Cu" "F.Mask" "F.Paste")
			(net "GND")
		)
		(pad "2" smd rect
			(at -0.40005 0 180)
			(size 0.4572 0.508)
			(layers "F.Cu" "F.Mask" "F.Paste")
			(net "PSU1_PS_ON_N")
		)
	)
	(footprint ""
		(layer "F.Cu")
		(at 71.518526 -105.26776 -90)
		(property "Reference" "C15"
			(at -3.25374 -0.008128 90)
			(unlocked yes)
			(layer "F.SilkS")
			(effects
				(font
					(size 0.7874 0.5842)
					(thickness 0.1524)
				)
			)
		)
		(property "Value" ""
			(at 0 0 270)
			(layer "F.Fab")
			(effects
				(font
					(size 1.27 1.27)
				)
			)
		)
		(duplicate_pad_numbers_are_jumpers no)
		(fp_line
			(start -1.2954 0.5842)
			(end -1.2954 -0.5842)
			(stroke
				(width 0.1524)
				(type default)
			)
			(layer "F.SilkS")
		)
		(fp_line
			(start 1.2954 0.5842)
			(end -1.2954 0.5842)
			(stroke
				(width 0.1524)
				(type default)
			)
			(layer "F.SilkS")
		)
		(fp_line
			(start -1.2954 -0.5842)
			(end 1.2954 -0.5842)
			(stroke
				(width 0.1524)
				(type default)
			)
			(layer "F.SilkS")
		)
		(fp_line
			(start 0 -0.5842)
			(end 0 0.5842)
			(stroke
				(width 0.1524)
				(type default)
			)
			(layer "F.SilkS")
		)
		(fp_line
			(start 1.2954 -0.5842)
			(end 1.2954 0.5842)
			(stroke
				(width 0.1524)
				(type default)
			)
			(layer "F.SilkS")
		)
		(fp_poly
			(pts
				(xy 0.8636 -0.4572) (xy 0.8636 -0.3556) (xy 1.143 -0.3556) (xy 1.143 0.3556) (xy 0.8636 0.3556)
				(xy 0.8636 0.4572) (xy -0.8636 0.4572) (xy -0.8636 0.3556) (xy -1.143 0.3556) (xy -1.143 -0.3556)
				(xy -0.8636 -0.3556) (xy -0.8636 -0.4572)
			)
			(stroke
				(width 0)
				(type default)
			)
			(fill no)
			(layer "F.CrtYd")
		)
		(fp_line
			(start -0.884936 0.504952)
			(end -0.884936 -0.504952)
			(stroke
				(width 0.1)
				(type default)
			)
			(layer "F.Fab")
		)
		(fp_line
			(start 0.884936 0.504952)
			(end -0.884936 0.504952)
			(stroke
				(width 0.1)
				(type default)
			)
			(layer "F.Fab")
		)
		(fp_line
			(start -0.884936 -0.504952)
			(end 0.884936 -0.504952)
			(stroke
				(width 0.1)
				(type default)
			)
			(layer "F.Fab")
		)
		(fp_line
			(start 0.884936 -0.504952)
			(end 0.884936 0.504952)
			(stroke
				(width 0.1)
				(type default)
			)
			(layer "F.Fab")
		)
		(pad "1" smd rect
			(at 0.7366 0)
			(size 0.7112 0.8128)
			(layers "F.Cu" "F.Mask" "F.Paste")
			(net "P12V")
		)
		(pad "2" smd rect
			(at -0.7366 0)
			(size 0.7112 0.8128)
			(layers "F.Cu" "F.Mask" "F.Paste")
			(net "GND")
		)
	)
	(footprint ""
		(layer "F.Cu")
		(at 26.18613 -190.368174)
		(property "Reference" "R136"
			(at -4.256532 0.268224 0)
			(unlocked yes)
			(layer "F.SilkS")
			(effects
				(font
					(size 0.7874 0.5842)
					(thickness 0.1524)
				)
				(justify left)
			)
		)
		(property "Value" ""
			(at 0 0 0)
			(layer "F.Fab")
			(effects
				(font
					(size 1.27 1.27)
				)
			)
		)
		(duplicate_pad_numbers_are_jumpers no)
		(fp_line
			(start -0.7874 -0.4064)
			(end 0.7874 -0.4064)
			(stroke
				(width 0.1524)
				(type default)
			)
			(layer "F.SilkS")
		)
		(fp_line
			(start -0.7874 0.4064)
			(end -0.7874 -0.4064)
			(stroke
				(width 0.1524)
				(type default)
			)
			(layer "F.SilkS")
		)
		(fp_line
			(start 0.7874 -0.4064)
			(end 0.7874 0.4064)
			(stroke
				(width 0.1524)
				(type default)
			)
			(layer "F.SilkS")
		)
		(fp_line
			(start 0.7874 0.4064)
			(end -0.7874 0.4064)
			(stroke
				(width 0.1524)
				(type default)
			)
			(layer "F.SilkS")
		)
		(fp_poly
			(pts
				(xy -0.508 0.2794) (xy -0.508 0.2286) (xy -0.635 0.2286) (xy -0.635 -0.254) (xy -0.5334 -0.254)
				(xy -0.5334 -0.2794) (xy 0.5334 -0.2794) (xy 0.5334 -0.254) (xy 0.635 -0.254) (xy 0.635 0.254) (xy 0.5334 0.254)
				(xy 0.5334 0.2794)
			)
			(stroke
				(width 0)
				(type default)
			)
			(fill no)
			(layer "F.CrtYd")
		)
		(pad "1" smd rect
			(at 0.40005 0)
			(size 0.4572 0.508)
			(layers "F.Cu" "F.Mask" "F.Paste")
			(net "PSU3_CSAHRE")
		)
		(pad "2" smd rect
			(at -0.40005 0)
			(size 0.4572 0.508)
			(layers "F.Cu" "F.Mask" "F.Paste")
			(net "PSU_CSAHRE")
		)
	)
	(footprint ""
		(layer "F.Cu")
		(at 16.599916 -206.99984)
		(property "Reference" "H2"
			(at -3.038856 -9.000998 0)
			(unlocked yes)
			(layer "F.SilkS")
			(effects
				(font
					(size 0.7874 0.5842)
					(thickness 0.1524)
				)
				(justify left)
			)
		)
		(property "Value" ""
			(at 0 0 0)
			(layer "F.Fab")
			(effects
				(font
					(size 1.27 1.27)
				)
			)
		)
		(duplicate_pad_numbers_are_jumpers no)
		(fp_circle
			(center 0 0)
			(end 7.999984 0)
			(stroke
				(width 0.1524)
				(type default)
			)
			(fill no)
			(layer "F.SilkS")
		)
		(fp_circle
			(center 0 0)
			(end 14.7066 0)
			(stroke
				(width 0.1524)
				(type default)
			)
			(fill no)
			(layer "B.SilkS")
		)
		(fp_poly
			(pts
				(arc
					(start 0 5.0038)
					(mid 0 -5.0038)
					(end 0 5.0038)
				)
			)
			(stroke
				(width 0)
				(type default)
			)
			(fill no)
			(layer "F.CrtYd")
		)
		(pad "" np_thru_hole circle
			(at 0 0)
			(size 4.0132 4.0132)
			(drill 4.0132)
			(layers "*.Cu" "*.Mask")
			(clearance 0.381)
			(thermal_gap 0.381)
		)
		(pad "2" thru_hole circle
			(at 0 -3.50012)
			(size 0.762 0.762)
			(drill 0.5588)
			(layers "*.Cu" "*.Mask")
			(remove_unused_layers no)
			(net "GND")
			(clearance 0.1524)
			(thermal_gap 0.1524)
		)
		(pad "3" thru_hole circle
			(at -2.500122 -2.500122)
			(size 0.762 0.762)
			(drill 0.5588)
			(layers "*.Cu" "*.Mask")
			(remove_unused_layers no)
			(net "GND")
			(clearance 0.1524)
			(thermal_gap 0.1524)
		)
		(pad "4" thru_hole circle
			(at -3.50012 0)
			(size 0.762 0.762)
			(drill 0.5588)
			(layers "*.Cu" "*.Mask")
			(remove_unused_layers no)
			(net "GND")
			(clearance 0.1524)
			(thermal_gap 0.1524)
		)
		(pad "5" thru_hole circle
			(at -2.500122 2.500122)
			(size 0.762 0.762)
			(drill 0.5588)
			(layers "*.Cu" "*.Mask")
			(remove_unused_layers no)
			(net "GND")
			(clearance 0.1524)
			(thermal_gap 0.1524)
		)
		(pad "6" thru_hole circle
			(at 0 3.50012)
			(size 0.762 0.762)
			(drill 0.5588)
			(layers "*.Cu" "*.Mask")
			(remove_unused_layers no)
			(net "GND")
			(clearance 0.1524)
			(thermal_gap 0.1524)
		)
		(pad "7" thru_hole circle
			(at 2.500122 2.500122)
			(size 0.762 0.762)
			(drill 0.5588)
			(layers "*.Cu" "*.Mask")
			(remove_unused_layers no)
			(net "GND")
			(clearance 0.1524)
			(thermal_gap 0.1524)
		)
		(pad "8" thru_hole circle
			(at 3.50012 0)
			(size 0.762 0.762)
			(drill 0.5588)
			(layers "*.Cu" "*.Mask")
			(remove_unused_layers no)
			(net "GND")
			(clearance 0.1524)
			(thermal_gap 0.1524)
		)
		(pad "9" thru_hole circle
			(at 2.500122 -2.500122)
			(size 0.762 0.762)
			(drill 0.5588)
			(layers "*.Cu" "*.Mask")
			(remove_unused_layers no)
			(net "GND")
			(clearance 0.1524)
			(thermal_gap 0.1524)
		)
		(zone
			(layer "F.Cu")
			(hatch none 0.5)
			(connect_pads
				(clearance 0)
			)
			(min_thickness 0.25)
			(keepout
				(tracks not_allowed)
				(vias allowed)
				(pads allowed)
				(copperpour not_allowed)
				(footprints allowed)
			)
			(placement
				(enabled no)
				(sheetname "")
			)
			(fill
				(thermal_gap 0.5)
				(thermal_bridge_width 0.5)
				(island_removal_mode 0)
			)
			(polygon
				(pts
					(arc
						(start 16.599916 -215.00084)
						(mid 8.598916 -206.99984)
						(end 16.599916 -198.99884)
					)
					(arc
						(start 16.599916 -198.99884)
						(mid 18.035016 -200.43394)
						(end 16.599916 -201.86904)
					)
					(arc
						(start 16.599916 -201.86904)
						(mid 11.469116 -206.99984)
						(end 16.599916 -212.13064)
					)
					(arc
						(start 16.599916 -212.13064)
						(mid 18.035016 -213.56574)
						(end 16.599916 -215.00084)
					)
				)
			)
		)
		(zone
			(layer "F.Cu")
			(hatch none 0.5)
			(connect_pads
				(clearance 0)
			)
			(min_thickness 0.25)
			(keepout
				(tracks not_allowed)
				(vias allowed)
				(pads allowed)
				(copperpour not_allowed)
				(footprints allowed)
			)
			(placement
				(enabled no)
				(sheetname "")
			)
			(fill
				(thermal_gap 0.5)
				(thermal_bridge_width 0.5)
				(island_removal_mode 0)
			)
			(polygon
				(pts
					(arc
						(start 16.599916 -215.00084)
						(mid 24.600916 -206.99984)
						(end 16.599916 -198.99884)
					)
					(arc
						(start 16.599916 -198.99884)
						(mid 15.164816 -200.43394)
						(end 16.599916 -201.86904)
					)
					(arc
						(start 16.599916 -201.86904)
						(mid 21.730716 -206.99984)
						(end 16.599916 -212.13064)
					)
					(arc
						(start 16.599916 -212.13064)
						(mid 15.164816 -213.56574)
						(end 16.599916 -215.00084)
					)
				)
			)
		)
		(zone
			(layers "F.Cu" "B.Cu" "In1.Cu" "In2.Cu" "In3.Cu" "In4.Cu" "In5.Cu" "In6.Cu")
			(hatch none 0.5)
			(connect_pads
				(clearance 0)
			)
			(min_thickness 0.25)
			(keepout
				(tracks not_allowed)
				(vias allowed)
				(pads allowed)
				(copperpour not_allowed)
				(footprints allowed)
			)
			(placement
				(enabled no)
				(sheetname "")
			)
			(fill
				(thermal_gap 0.5)
				(thermal_bridge_width 0.5)
				(island_removal_mode 0)
			)
			(polygon
				(pts
					(arc
						(start 16.599916 -204.48778)
						(mid 16.599916 -209.5119)
						(end 16.599916 -204.48778)
					)
				)
			)
		)
	)
	(footprint ""
		(layer "F.Cu")
		(at 51.613054 -240.589308 180)
		(property "Reference" "CE12"
			(at -5.020056 0.183388 0)
			(unlocked yes)
			(layer "F.SilkS")
			(effects
				(font
					(size 0.7874 0.5842)
					(thickness 0.1524)
				)
				(justify left)
			)
		)
		(property "Value" ""
			(at 0 0 180)
			(layer "F.Fab")
			(effects
				(font
					(size 1.27 1.27)
				)
			)
		)
		(duplicate_pad_numbers_are_jumpers no)
		(fp_line
			(start 0 -4.2672)
			(end 0 4.2672)
			(stroke
				(width 0.1524)
				(type default)
			)
			(layer "F.SilkS")
		)
		(fp_circle
			(center 0 0)
			(end -4.2672 0)
			(stroke
				(width 0.1524)
				(type default)
			)
			(fill no)
			(layer "F.SilkS")
		)
		(fp_poly
			(pts
				(arc
					(start 0 -4.2672)
					(mid 4.2672 0)
					(end 0 4.2672)
				)
			)
			(stroke
				(width 0)
				(type default)
			)
			(fill yes)
			(layer "F.SilkS")
		)
		(fp_poly
			(pts
				(xy -2.5146 -0.762) (xy -0.9906 -0.762) (xy -0.9906 0.762) (xy -2.5146 0.762)
			)
			(stroke
				(width 0)
				(type default)
			)
			(fill no)
			(layer "B.CrtYd")
		)
		(fp_poly
			(pts
				(arc
					(start 1.7526 0.762)
					(mid 2.291415 -0.538815)
					(end 0.9906 0)
				)
				(arc
					(start 0.9906 0.0254)
					(mid 1.206345 0.546255)
					(end 1.7272 0.762)
				)
			)
			(stroke
				(width 0)
				(type default)
			)
			(fill no)
			(layer "B.CrtYd")
		)
		(fp_poly
			(pts
				(arc
					(start -4.2672 0)
					(mid 4.2672 0)
					(end -4.2672 0)
				)
			)
			(stroke
				(width 0)
				(type default)
			)
			(fill no)
			(layer "F.CrtYd")
		)
		(fp_circle
			(center 0 0)
			(end -4.2672 0)
			(stroke
				(width 0.1)
				(type default)
			)
			(fill no)
			(layer "F.Fab")
		)
		(fp_text user "+"
			(at -6.029198 -1.306322 180)
			(unlocked yes)
			(layer "F.SilkS")
			(effects
				(font
					(size 0.7874 0.5842)
					(thickness 0.1524)
				)
				(justify left)
			)
		)
		(fp_text user "+"
			(at -5.6642 -0.34925 180)
			(unlocked yes)
			(layer "F.Fab")
			(effects
				(font
					(size 1.905 1.4224)
					(thickness 0.000001)
				)
				(justify left)
			)
		)
		(pad "1" thru_hole rect
			(at -1.75006 0 180)
			(size 1.397 1.397)
			(drill 0.9144)
			(layers "*.Cu" "*.Mask")
			(remove_unused_layers no)
			(net "P12V")
			(clearance 0.0127)
			(thermal_gap 0.0127)
			(padstack
				(mode front_inner_back)
				(layer "Inner"
					(shape circle)
					(size 1.397 1.397)
					(clearance 0.0127)
				)
				(layer "B.Cu"
					(shape rect)
					(size 1.397 1.397)
					(clearance 0.0127)
				)
			)
		)
		(pad "2" thru_hole circle
			(at 1.75006 0 180)
			(size 1.397 1.397)
			(drill 0.9144)
			(layers "*.Cu" "*.Mask")
			(remove_unused_layers no)
			(net "GND")
			(clearance 0.0127)
			(thermal_gap 0.0127)
		)
	)
	(footprint ""
		(layer "F.Cu")
		(at 70.71487 -131.443476 90)
		(property "Reference" "C26"
			(at -3.829812 0.066294 90)
			(unlocked yes)
			(layer "F.SilkS")
			(effects
				(font
					(size 0.7874 0.5842)
					(thickness 0.1524)
				)
				(justify left)
			)
		)
		(property "Value" ""
			(at 0 0 90)
			(layer "F.Fab")
			(effects
				(font
					(size 1.27 1.27)
				)
			)
		)
		(duplicate_pad_numbers_are_jumpers no)
		(fp_line
			(start 0.7874 -0.4064)
			(end 0.7874 0.4064)
			(stroke
				(width 0.1524)
				(type default)
			)
			(layer "F.SilkS")
		)
		(fp_line
			(start -0.7874 -0.4064)
			(end 0.7874 -0.4064)
			(stroke
				(width 0.1524)
				(type default)
			)
			(layer "F.SilkS")
		)
		(fp_line
			(start 0 0.381)
			(end 0 -0.381)
			(stroke
				(width 0.1524)
				(type default)
			)
			(layer "F.SilkS")
		)
		(fp_line
			(start 0.7874 0.4064)
			(end -0.7874 0.4064)
			(stroke
				(width 0.1524)
				(type default)
			)
			(layer "F.SilkS")
		)
		(fp_line
			(start -0.7874 0.4064)
			(end -0.7874 -0.4064)
			(stroke
				(width 0.1524)
				(type default)
			)
			(layer "F.SilkS")
		)
		(fp_poly
			(pts
				(xy -0.5334 0.254) (xy -0.635 0.254) (xy -0.635 0.2286) (xy -0.635 -0.254) (xy -0.5334 -0.254) (xy -0.5334 -0.2794)
				(xy 0.5334 -0.2794) (xy 0.5334 -0.254) (xy 0.635 -0.254) (xy 0.635 0.254) (xy 0.5334 0.254) (xy 0.5334 0.2794)
				(xy -0.508 0.2794) (xy -0.5334 0.2794)
			)
			(stroke
				(width 0)
				(type default)
			)
			(fill no)
			(layer "F.CrtYd")
		)
		(pad "1" smd rect
			(at 0.40005 0 90)
			(size 0.4572 0.508)
			(layers "F.Cu" "F.Mask" "F.Paste")
			(net "P12V")
		)
		(pad "2" smd rect
			(at -0.40005 0 90)
			(size 0.4572 0.508)
			(layers "F.Cu" "F.Mask" "F.Paste")
			(net "GND")
		)
	)
)
